# SCM (Grand Teton) — schematic netlist excerpt (pin names and nets, part order shuffled) for the footprints in the layout excerpt that follows; sources: Cadence DE-HDL packaged netlist, KiCad conversion of 12092022_DA0F0TMDCD0_F0T_Management_Board_D_brd_V3_OCP.brd

R442  Q_RES  33.2 1% CHIP  pkg 0402LF  page 13 : A = SMB_BMC_ALERT3_N ; B = SMB_BMC_ALERT3_R_N
R291  Q_RES  4.7K 1% CHIP  pkg 0402LF  page 22 : A = P3V3_RGM ; B = RST_BMC_EXTRST_R1_N

(kicad_pcb
	(version 20260206)
	(generator "pcbnew")
	(generator_version "10.0")
	(general
		(thickness 1.6)
		(legacy_teardrops no)
	)
	(paper "A4")
	(title_block
		(title "12092022_DA0F0TMDCD0_F0T_Management_Board_D_brd_V3_OCP.brd")
		(comment 1 "Grand Teton / footprints 25-26 of 1440")
	)
	(layers
		(0 "F.Cu" signal "TOP")
		(4 "In1.Cu" signal "GND")
		(6 "In2.Cu" signal "IN1")
		(8 "In3.Cu" signal "GND1")
		(10 "In4.Cu" signal "IN2")
		(12 "In5.Cu" signal "VCC")
		(14 "In6.Cu" signal "VCC1")
		(16 "In7.Cu" signal "IN3")
		(18 "In8.Cu" signal "GND2")
		(20 "In9.Cu" signal "IN4")
		(22 "In10.Cu" signal "GND3")
		(2 "B.Cu" signal "BOTTOM")
		(9 "F.Adhes" user "F.Adhesive")
		(11 "B.Adhes" user "B.Adhesive")
		(13 "F.Paste" user "Package Geometry/Pastemask Top")
		(15 "B.Paste" user "Package Geometry/Pastemask Bottom")
		(5 "F.SilkS" user "Ref Des/Silkscreen Top")
		(7 "B.SilkS" user "Ref Des/Silkscreen Bottom")
		(1 "F.Mask" user "Board Geometry/Soldermask Top")
		(3 "B.Mask" user "Board Geometry/Soldermask Bottom")
		(17 "Dwgs.User" user "User.Drawings")
		(19 "Cmts.User" user "User.Comments")
		(21 "Eco1.User" user "User.Eco1")
		(23 "Eco2.User" user "User.Eco2")
		(25 "Edge.Cuts" user "Board Geometry/Outline")
		(27 "Margin" user)
		(31 "F.CrtYd" user "Package Geometry/Place Bound Top")
		(29 "B.CrtYd" user "Package Geometry/Place Bound Bottom")
		(35 "F.Fab" user "Ref Des/Assembly Top")
		(33 "B.Fab" user "Ref Des/Assembly Bottom")
	)
	(footprint ""
		(layer "F.Cu")
		(at 49.2125 -93.9165 -90)
		(property "Reference" "R291"
			(at 0 0 270)
			(layer "F.SilkS")
			(hide yes)
			(effects
				(font
					(size 1.27 1.27)
				)
			)
		)
		(property "Value" ""
			(at 0 0 270)
			(layer "F.Fab")
			(effects
				(font
					(size 1.27 1.27)
				)
			)
		)
		(duplicate_pad_numbers_are_jumpers no)
		(fp_line
			(start -0.7874 0.4064)
			(end -0.7874 -0.4064)
			(stroke
				(width 0.1524)
				(type default)
			)
			(layer "F.SilkS")
		)
		(fp_line
			(start 0.7874 0.4064)
			(end -0.7874 0.4064)
			(stroke
				(width 0.1524)
				(type default)
			)
			(layer "F.SilkS")
		)
		(fp_line
			(start -0.7874 -0.4064)
			(end 0.7874 -0.4064)
			(stroke
				(width 0.1524)
				(type default)
			)
			(layer "F.SilkS")
		)
		(fp_line
			(start 0.7874 -0.4064)
			(end 0.7874 0.4064)
			(stroke
				(width 0.1524)
				(type default)
			)
			(layer "F.SilkS")
		)
		(fp_line
			(start -0.67945 0.3048)
			(end -0.67945 -0.305054)
			(stroke
				(width 0.1)
				(type default)
			)
			(layer "F.Fab")
		)
		(fp_line
			(start -0.12065 0.3048)
			(end -0.67945 0.3048)
			(stroke
				(width 0.1)
				(type default)
			)
			(layer "F.Fab")
		)
		(fp_line
			(start 0.120396 0.3048)
			(end 0.120396 0.2794)
			(stroke
				(width 0.1)
				(type default)
			)
			(layer "F.Fab")
		)
		(fp_line
			(start 0.67945 0.3048)
			(end 0.120396 0.3048)
			(stroke
				(width 0.1)
				(type default)
			)
			(layer "F.Fab")
		)
		(fp_line
			(start -0.12065 0.2794)
			(end -0.12065 0.3048)
			(stroke
				(width 0.1)
				(type default)
			)
			(layer "F.Fab")
		)
		(fp_line
			(start 0.120396 0.2794)
			(end -0.12065 0.2794)
			(stroke
				(width 0.1)
				(type default)
			)
			(layer "F.Fab")
		)
		(fp_line
			(start -0.12065 -0.2794)
			(end 0.12065 -0.2794)
			(stroke
				(width 0.1)
				(type default)
			)
			(layer "F.Fab")
		)
		(fp_line
			(start 0.12065 -0.2794)
			(end 0.12065 -0.3048)
			(stroke
				(width 0.1)
				(type default)
			)
			(layer "F.Fab")
		)
		(fp_line
			(start 0.12065 -0.3048)
			(end 0.67945 -0.3048)
			(stroke
				(width 0.1)
				(type default)
			)
			(layer "F.Fab")
		)
		(fp_line
			(start 0.67945 -0.3048)
			(end 0.67945 0.3048)
			(stroke
				(width 0.1)
				(type default)
			)
			(layer "F.Fab")
		)
		(fp_line
			(start -0.67945 -0.305054)
			(end -0.12065 -0.305054)
			(stroke
				(width 0.1)
				(type default)
			)
			(layer "F.Fab")
		)
		(fp_line
			(start -0.12065 -0.305054)
			(end -0.12065 -0.2794)
			(stroke
				(width 0.1)
				(type default)
			)
			(layer "F.Fab")
		)
		(pad "1" smd circle
			(at -0.40005 0 270)
			(size 0 0)
			(layers "F.Cu" "F.Mask" "F.Paste")
			(net "P3V3_RGM")
		)
		(pad "2" smd circle
			(at 0.40005 0 270)
			(size 0 0)
			(layers "F.Cu" "F.Mask" "F.Paste")
			(net "RST_BMC_EXTRST_R1_N")
		)
	)
	(footprint ""
		(layer "F.Cu")
		(at 39.9034 -41.5036)
		(property "Reference" "R442"
			(at 0 0 0)
			(layer "F.SilkS")
			(hide yes)
			(effects
				(font
					(size 1.27 1.27)
				)
			)
		)
		(property "Value" ""
			(at 0 0 0)
			(layer "F.Fab")
			(effects
				(font
					(size 1.27 1.27)
				)
			)
		)
		(duplicate_pad_numbers_are_jumpers no)
		(fp_line
			(start -0.7874 -0.4064)
			(end 0.7874 -0.4064)
			(stroke
				(width 0.1524)
				(type default)
			)
			(layer "F.SilkS")
		)
		(fp_line
			(start -0.7874 0.4064)
			(end -0.7874 -0.4064)
			(stroke
				(width 0.1524)
				(type default)
			)
			(layer "F.SilkS")
		)
		(fp_line
			(start 0.7874 -0.4064)
			(end 0.7874 0.4064)
			(stroke
				(width 0.1524)
				(type default)
			)
			(layer "F.SilkS")
		)
		(fp_line
			(start 0.7874 0.4064)
			(end -0.7874 0.4064)
			(stroke
				(width 0.1524)
				(type default)
			)
			(layer "F.SilkS")
		)
		(fp_line
			(start -0.67945 -0.305054)
			(end -0.12065 -0.305054)
			(stroke
				(width 0.1)
				(type default)
			)
			(layer "F.Fab")
		)
		(fp_line
			(start -0.67945 0.3048)
			(end -0.67945 -0.305054)
			(stroke
				(width 0.1)
				(type default)
			)
			(layer "F.Fab")
		)
		(fp_line
			(start -0.12065 -0.305054)
			(end -0.12065 -0.2794)
			(stroke
				(width 0.1)
				(type default)
			)
			(layer "F.Fab")
		)
		(fp_line
			(start -0.12065 -0.2794)
			(end 0.12065 -0.2794)
			(stroke
				(width 0.1)
				(type default)
			)
			(layer "F.Fab")
		)
		(fp_line
			(start -0.12065 0.2794)
			(end -0.12065 0.3048)
			(stroke
				(width 0.1)
				(type default)
			)
			(layer "F.Fab")
		)
		(fp_line
			(start -0.12065 0.3048)
			(end -0.67945 0.3048)
			(stroke
				(width 0.1)
				(type default)
			)
			(layer "F.Fab")
		)
		(fp_line
			(start 0.120396 0.2794)
			(end -0.12065 0.2794)
			(stroke
				(width 0.1)
				(type default)
			)
			(layer "F.Fab")
		)
		(fp_line
			(start 0.120396 0.3048)
			(end 0.120396 0.2794)
			(stroke
				(width 0.1)
				(type default)
			)
			(layer "F.Fab")
		)
		(fp_line
			(start 0.12065 -0.3048)
			(end 0.67945 -0.3048)
			(stroke
				(width 0.1)
				(type default)
			)
			(layer "F.Fab")
		)
		(fp_line
			(start 0.12065 -0.2794)
			(end 0.12065 -0.3048)
			(stroke
				(width 0.1)
				(type default)
			)
			(layer "F.Fab")
		)
		(fp_line
			(start 0.67945 -0.3048)
			(end 0.67945 0.3048)
			(stroke
				(width 0.1)
				(type default)
			)
			(layer "F.Fab")
		)
		(fp_line
			(start 0.67945 0.3048)
			(end 0.120396 0.3048)
			(stroke
				(width 0.1)
				(type default)
			)
			(layer "F.Fab")
		)
		(pad "1" smd circle
			(at -0.40005 0)
			(size 0 0)
			(layers "F.Cu" "F.Mask" "F.Paste")
			(net "SMB_BMC_ALERT3_N")
		)
		(pad "2" smd circle
			(at 0.40005 0)
			(size 0 0)
			(layers "F.Cu" "F.Mask" "F.Paste")
			(net "SMB_BMC_ALERT3_R_N")
		)
	)
)
